(kicad_pcb
	(version 20241229)
	(generator "pcbnew")
	(generator_version "9.0")
	(general
		(thickness 1.61)
		(legacy_teardrops no)
	)
	(paper "A3")
	(title_block
		(title "SO-DIMM DDR5 Tester")
		(date "2025-11-26")
		(rev "1.3.0")
		(comment 9 "footprints 449-454 of 627")
	)
	(layers
		(0 "F.Cu" signal)
		(4 "In1.Cu" power)
		(6 "In2.Cu" mixed)
		(8 "In3.Cu" power)
		(10 "In4.Cu" mixed)
		(12 "In5.Cu" power)
		(14 "In6.Cu" mixed)
		(16 "In7.Cu" power)
		(18 "In8.Cu" power)
		(20 "In9.Cu" mixed)
		(22 "In10.Cu" power)
		(2 "B.Cu" signal)
		(9 "F.Adhes" user "F.Adhesive")
		(11 "B.Adhes" user "B.Adhesive")
		(13 "F.Paste" user)
		(15 "B.Paste" user)
		(5 "F.SilkS" user "F.Silkscreen")
		(7 "B.SilkS" user "B.Silkscreen")
		(1 "F.Mask" user)
		(3 "B.Mask" user)
		(17 "Dwgs.User" user "User.Drawings")
		(19 "Cmts.User" user "User.Comments")
		(21 "Eco1.User" user "User.Eco1")
		(23 "Eco2.User" user "User.Eco2")
		(25 "Edge.Cuts" user)
		(27 "Margin" user)
		(31 "F.CrtYd" user "F.Courtyard")
		(29 "B.CrtYd" user "B.Courtyard")
		(35 "F.Fab" user)
		(33 "B.Fab" user)
	)
	(footprint "antmicro-footprints:C_0402_1005Metric"
		(layer "B.Cu")
		(at 137.375501 184.801 -90)
		(descr "Capacitor SMD 0402 (1005 Metric), square (rectangular) end terminal, IPC_7351 nominal, (Body size source: IPC-SM-782 page 76, https://www.pcb-3d.com/wordpress/wp-content/uploads/ipc-sm-782a_amendment_1_and_2.pdf)")
		(tags "capacitor 0402")
		(property "Reference" "C59"
			(at 0 1.17 90)
			(layer "B.SilkS")
			(hide yes)
			(effects
				(font
					(size 0.7 0.7)
					(thickness 0.15)
				)
				(justify left bottom mirror)
			)
		)
		(property "Value" "C_100n_0402"
			(at 0 -1.169 90)
			(layer "B.Fab")
			(effects
				(font
					(size 0.7 0.7)
					(thickness 0.15)
				)
				(justify left bottom mirror)
			)
		)
		(property "Datasheet" "https://www.murata.com/products/productdetail?partno=GRM155R61H104KE14%23"
			(at 0 0 270)
			(layer "F.Fab")
			(hide yes)
			(effects
				(font
					(size 1.27 1.27)
					(thickness 0.15)
				)
			)
		)
		(property "Author" "Antmicro"
			(at -47.425499 322.176501 0)
			(layer "B.Fab")
			(hide yes)
			(effects
				(font
					(size 1 1)
					(thickness 0.15)
				)
				(justify mirror)
			)
		)
		(property "Dielectric" "X5R"
			(at -47.425499 322.176501 0)
			(layer "B.Fab")
			(hide yes)
			(effects
				(font
					(size 1 1)
					(thickness 0.15)
				)
				(justify mirror)
			)
		)
		(property "License" "Apache-2.0"
			(at -47.425499 322.176501 0)
			(layer "B.Fab")
			(hide yes)
			(effects
				(font
					(size 1 1)
					(thickness 0.15)
				)
				(justify mirror)
			)
		)
		(property "MPN" "GRM155R61H104KE14D"
			(at -47.425499 322.176501 0)
			(layer "B.Fab")
			(hide yes)
			(effects
				(font
					(size 1 1)
					(thickness 0.15)
				)
				(justify mirror)
			)
		)
		(property "Manufacturer" "Murata"
			(at -47.425499 322.176501 0)
			(layer "B.Fab")
			(hide yes)
			(effects
				(font
					(size 1 1)
					(thickness 0.15)
				)
				(justify mirror)
			)
		)
		(property "Val" "100n"
			(at -47.425499 322.176501 0)
			(layer "B.Fab")
			(hide yes)
			(effects
				(font
					(size 1 1)
					(thickness 0.15)
				)
				(justify mirror)
			)
		)
		(property "Voltage" "50V"
			(at -47.425499 322.176501 0)
			(layer "B.Fab")
			(hide yes)
			(effects
				(font
					(size 1 1)
					(thickness 0.15)
				)
				(justify mirror)
			)
		)
		(sheetname "/FPGA power/")
		(sheetfile "fpga-power.kicad_sch")
		(attr smd)
		(fp_rect
			(start -0.9656 0.4572)
			(end 0.9652 -0.4828)
			(stroke
				(width 0.05)
				(type solid)
			)
			(fill no)
			(layer "B.CrtYd")
		)
		(fp_line
			(start -0.5 0.25)
			(end 0.498 0.25)
			(stroke
				(width 0.15)
				(type solid)
			)
			(layer "B.Fab")
		)
		(fp_line
			(start 0.498 0.25)
			(end 0.498 -0.248)
			(stroke
				(width 0.15)
				(type solid)
			)
			(layer "B.Fab")
		)
		(fp_line
			(start -0.5 -0.248)
			(end -0.5 0.25)
			(stroke
				(width 0.15)
				(type solid)
			)
			(layer "B.Fab")
		)
		(fp_line
			(start 0.498 -0.248)
			(end -0.5 -0.248)
			(stroke
				(width 0.15)
				(type solid)
			)
			(layer "B.Fab")
		)
		(pad "1" smd roundrect
			(at -0.5 0 180)
			(size 0.6 0.6)
			(layers "B.Cu" "B.Mask" "B.Paste")
			(roundrect_rratio 0.25)
			(net 1 "GND")
			(pintype "passive")
		)
		(pad "2" smd roundrect
			(at 0.498 0 270)
			(size 0.6 0.6)
			(layers "B.Cu" "B.Mask" "B.Paste")
			(roundrect_rratio 0.25)
			(net 200 "+3V3")
			(pintype "passive")
		)
	)
	(footprint "antmicro-footprints:C_0402_1005Metric"
		(layer "B.Cu")
		(at 197.665 145.801)
		(descr "Capacitor SMD 0402")
		(tags "capacitor SMD 0402")
		(property "Reference" "C209"
			(at 0 0.699 180)
			(layer "B.SilkS")
			(hide yes)
			(effects
				(font
					(size 0.7 0.7)
					(thickness 0.15)
				)
				(justify left bottom mirror)
			)
		)
		(property "Value" "C_100n_0402"
			(at -1.022927 -2.155213 180)
			(layer "B.Fab")
			(effects
				(font
					(size 0.7 0.7)
					(thickness 0.15)
				)
				(justify left bottom mirror)
			)
		)
		(property "Datasheet" "https://www.murata.com/products/productdetail?partno=GRM155R61H104KE14%23"
			(at 0 0 0)
			(layer "F.Fab")
			(hide yes)
			(effects
				(font
					(size 1.27 1.27)
					(thickness 0.15)
				)
			)
		)
		(property "Author" "Antmicro"
			(at 0 0 0)
			(layer "B.Fab")
			(hide yes)
			(effects
				(font
					(size 1 1)
					(thickness 0.15)
				)
				(justify mirror)
			)
		)
		(property "Dielectric" "X5R"
			(at 0 0 0)
			(layer "B.Fab")
			(hide yes)
			(effects
				(font
					(size 1 1)
					(thickness 0.15)
				)
				(justify mirror)
			)
		)
		(property "License" "Apache-2.0"
			(at 0 0 0)
			(layer "B.Fab")
			(hide yes)
			(effects
				(font
					(size 1 1)
					(thickness 0.15)
				)
				(justify mirror)
			)
		)
		(property "MPN" "GRM155R61H104KE14D"
			(at 0 0 0)
			(layer "B.Fab")
			(hide yes)
			(effects
				(font
					(size 1 1)
					(thickness 0.15)
				)
				(justify mirror)
			)
		)
		(property "Manufacturer" "Murata"
			(at 0 0 0)
			(layer "B.Fab")
			(hide yes)
			(effects
				(font
					(size 1 1)
					(thickness 0.15)
				)
				(justify mirror)
			)
		)
		(property "Val" "100n"
			(at 0 0 0)
			(layer "B.Fab")
			(hide yes)
			(effects
				(font
					(size 1 1)
					(thickness 0.15)
				)
				(justify mirror)
			)
		)
		(property "Voltage" "50V"
			(at 0 0 0)
			(layer "B.Fab")
			(hide yes)
			(effects
				(font
					(size 1 1)
					(thickness 0.15)
				)
				(justify mirror)
			)
		)
		(sheetname "/Supply/")
		(sheetfile "supply.kicad_sch")
		(attr smd)
		(fp_rect
			(start -0.9659 0.481258)
			(end 0.9649 -0.458742)
			(stroke
				(width 0.05)
				(type solid)
			)
			(fill no)
			(layer "B.CrtYd")
		)
		(fp_line
			(start -0.499 -0.248)
			(end -0.499 0.25)
			(stroke
				(width 0.15)
				(type solid)
			)
			(layer "B.Fab")
		)
		(fp_line
			(start -0.499 0.25)
			(end 0.499 0.25)
			(stroke
				(width 0.15)
				(type solid)
			)
			(layer "B.Fab")
		)
		(fp_line
			(start 0.499 -0.248)
			(end -0.499 -0.248)
			(stroke
				(width 0.15)
				(type solid)
			)
			(layer "B.Fab")
		)
		(fp_line
			(start 0.499 0.25)
			(end 0.499 -0.248)
			(stroke
				(width 0.15)
				(type solid)
			)
			(layer "B.Fab")
		)
		(pad "1" smd roundrect
			(at -0.484 0)
			(size 0.59 0.64)
			(layers "B.Cu" "B.Mask" "B.Paste")
			(roundrect_rratio 0.25)
			(net 1 "GND")
			(pintype "passive")
		)
		(pad "2" smd roundrect
			(at 0.484 0)
			(size 0.59 0.64)
			(layers "B.Cu" "B.Mask" "B.Paste")
			(roundrect_rratio 0.25)
			(net 62 "/Supply/SEQ_EN")
			(pintype "passive")
		)
	)
	(footprint "antmicro-footprints:C_0402_1005Metric"
		(layer "B.Cu")
		(at 130.375501 183.8005 -90)
		(descr "Capacitor SMD 0402 (1005 Metric), square (rectangular) end terminal, IPC_7351 nominal, (Body size source: IPC-SM-782 page 76, https://www.pcb-3d.com/wordpress/wp-content/uploads/ipc-sm-782a_amendment_1_and_2.pdf)")
		(tags "capacitor 0402")
		(property "Reference" "C41"
			(at 0 1.17 90)
			(layer "B.SilkS")
			(hide yes)
			(effects
				(font
					(size 0.7 0.7)
					(thickness 0.15)
				)
				(justify left bottom mirror)
			)
		)
		(property "Value" "C_100n_0402"
			(at 0 -1.169 90)
			(layer "B.Fab")
			(effects
				(font
					(size 0.7 0.7)
					(thickness 0.15)
				)
				(justify left bottom mirror)
			)
		)
		(property "Datasheet" "https://www.murata.com/products/productdetail?partno=GRM155R61H104KE14%23"
			(at 0 0 270)
			(layer "F.Fab")
			(hide yes)
			(effects
				(font
					(size 1.27 1.27)
					(thickness 0.15)
				)
			)
		)
		(property "Author" "Antmicro"
			(at -53.424999 314.176001 0)
			(layer "B.Fab")
			(hide yes)
			(effects
				(font
					(size 1 1)
					(thickness 0.15)
				)
				(justify mirror)
			)
		)
		(property "Dielectric" "X5R"
			(at -53.424999 314.176001 0)
			(layer "B.Fab")
			(hide yes)
			(effects
				(font
					(size 1 1)
					(thickness 0.15)
				)
				(justify mirror)
			)
		)
		(property "License" "Apache-2.0"
			(at -53.424999 314.176001 0)
			(layer "B.Fab")
			(hide yes)
			(effects
				(font
					(size 1 1)
					(thickness 0.15)
				)
				(justify mirror)
			)
		)
		(property "MPN" "GRM155R61H104KE14D"
			(at -53.424999 314.176001 0)
			(layer "B.Fab")
			(hide yes)
			(effects
				(font
					(size 1 1)
					(thickness 0.15)
				)
				(justify mirror)
			)
		)
		(property "Manufacturer" "Murata"
			(at -53.424999 314.176001 0)
			(layer "B.Fab")
			(hide yes)
			(effects
				(font
					(size 1 1)
					(thickness 0.15)
				)
				(justify mirror)
			)
		)
		(property "Val" "100n"
			(at -53.424999 314.176001 0)
			(layer "B.Fab")
			(hide yes)
			(effects
				(font
					(size 1 1)
					(thickness 0.15)
				)
				(justify mirror)
			)
		)
		(property "Voltage" "50V"
			(at -53.424999 314.176001 0)
			(layer "B.Fab")
			(hide yes)
			(effects
				(font
					(size 1 1)
					(thickness 0.15)
				)
				(justify mirror)
			)
		)
		(sheetname "/FPGA power/")
		(sheetfile "fpga-power.kicad_sch")
		(attr smd)
		(fp_rect
			(start -0.9656 0.4572)
			(end 0.9652 -0.4828)
			(stroke
				(width 0.05)
				(type solid)
			)
			(fill no)
			(layer "B.CrtYd")
		)
		(fp_line
			(start -0.5 0.25)
			(end 0.498 0.25)
			(stroke
				(width 0.15)
				(type solid)
			)
			(layer "B.Fab")
		)
		(fp_line
			(start 0.498 0.25)
			(end 0.498 -0.248)
			(stroke
				(width 0.15)
				(type solid)
			)
			(layer "B.Fab")
		)
		(fp_line
			(start -0.5 -0.248)
			(end -0.5 0.25)
			(stroke
				(width 0.15)
				(type solid)
			)
			(layer "B.Fab")
		)
		(fp_line
			(start 0.498 -0.248)
			(end -0.5 -0.248)
			(stroke
				(width 0.15)
				(type solid)
			)
			(layer "B.Fab")
		)
		(pad "1" smd roundrect
			(at -0.5 0 180)
			(size 0.6 0.6)
			(layers "B.Cu" "B.Mask" "B.Paste")
			(roundrect_rratio 0.25)
			(net 1 "GND")
			(pintype "passive")
		)
		(pad "2" smd roundrect
			(at 0.498 0 270)
			(size 0.6 0.6)
			(layers "B.Cu" "B.Mask" "B.Paste")
			(roundrect_rratio 0.25)
			(net 200 "+3V3")
			(pintype "passive")
		)
	)
	(footprint "antmicro-footprints:TP_SMD_1mm"
		(layer "B.Cu")
		(at 124.2 184.8 180)
		(property "Reference" "TP24"
			(at 0 0.731898 0)
			(layer "B.SilkS")
			(hide yes)
			(effects
				(font
					(size 0.7 0.7)
					(thickness 0.15)
				)
				(justify left bottom mirror)
			)
		)
		(property "Value" "TP_1mm_SMD"
			(at 0 -1.4 0)
			(layer "B.Fab")
			(effects
				(font
					(size 0.7 0.7)
					(thickness 0.15)
				)
				(justify left bottom mirror)
			)
		)
		(property "Author" "Antmicro"
			(at 248.4 369.6 0)
			(layer "B.Fab")
			(hide yes)
			(effects
				(font
					(size 1 1)
					(thickness 0.15)
				)
				(justify mirror)
			)
		)
		(property "License" "Apache-2.0"
			(at 248.4 369.6 0)
			(layer "B.Fab")
			(hide yes)
			(effects
				(font
					(size 1 1)
					(thickness 0.15)
				)
				(justify mirror)
			)
		)
		(property "MPN" ""
			(at 248.4 369.6 0)
			(layer "B.Fab")
			(hide yes)
			(effects
				(font
					(size 1 1)
					(thickness 0.15)
				)
				(justify mirror)
			)
		)
		(property "Manufacturer" ""
			(at 248.4 369.6 0)
			(layer "B.Fab")
			(hide yes)
			(effects
				(font
					(size 1 1)
					(thickness 0.15)
				)
				(justify mirror)
			)
		)
		(sheetname "/FPGA bank 14/")
		(sheetfile "fpga-bank-14.kicad_sch")
		(attr exclude_from_pos_files)
		(pad "1" smd circle
			(at 0 0 180)
			(size 1 1)
			(layers "B.Cu" "B.Mask")
			(net 44 "/FPGA bank 14/EMCCLK")
			(pinfunction "1")
			(pintype "passive")
		)
	)
	(footprint "antmicro-footprints:C_0402_1005Metric"
		(layer "B.Cu")
		(at 140.375501 177.801 90)
		(descr "Capacitor SMD 0402 (1005 Metric), square (rectangular) end terminal, IPC_7351 nominal, (Body size source: IPC-SM-782 page 76, https://www.pcb-3d.com/wordpress/wp-content/uploads/ipc-sm-782a_amendment_1_and_2.pdf)")
		(tags "capacitor 0402")
		(property "Reference" "C71"
			(at 0 1.17 270)
			(layer "B.SilkS")
			(hide yes)
			(effects
				(font
					(size 0.7 0.7)
					(thickness 0.15)
				)
				(justify left bottom mirror)
			)
		)
		(property "Value" "C_4u7_0402"
			(at 0 -1.169 270)
			(layer "B.Fab")
			(effects
				(font
					(size 0.7 0.7)
					(thickness 0.15)
				)
				(justify left bottom mirror)
			)
		)
		(property "Datasheet" "https://www.murata.com/products/productdetail?partno=GRM155R61A475MEAA%23"
			(at 0 0 90)
			(layer "F.Fab")
			(hide yes)
			(effects
				(font
					(size 1.27 1.27)
					(thickness 0.15)
				)
			)
		)
		(property "Author" "Antmicro"
			(at 318.176501 37.425499 0)
			(layer "B.Fab")
			(hide yes)
			(effects
				(font
					(size 1 1)
					(thickness 0.15)
				)
				(justify mirror)
			)
		)
		(property "Dielectric" ""
			(at 318.176501 37.425499 0)
			(layer "B.Fab")
			(hide yes)
			(effects
				(font
					(size 1 1)
					(thickness 0.15)
				)
				(justify mirror)
			)
		)
		(property "License" "Apache-2.0"
			(at 318.176501 37.425499 0)
			(layer "B.Fab")
			(hide yes)
			(effects
				(font
					(size 1 1)
					(thickness 0.15)
				)
				(justify mirror)
			)
		)
		(property "MPN" "GRM155R61A475MEAAD"
			(at 318.176501 37.425499 0)
			(layer "B.Fab")
			(hide yes)
			(effects
				(font
					(size 1 1)
					(thickness 0.15)
				)
				(justify mirror)
			)
		)
		(property "Manufacturer" "Murata"
			(at 318.176501 37.425499 0)
			(layer "B.Fab")
			(hide yes)
			(effects
				(font
					(size 1 1)
					(thickness 0.15)
				)
				(justify mirror)
			)
		)
		(property "Val" "4u7"
			(at 318.176501 37.425499 0)
			(layer "B.Fab")
			(hide yes)
			(effects
				(font
					(size 1 1)
					(thickness 0.15)
				)
				(justify mirror)
			)
		)
		(property "Voltage" ""
			(at 318.176501 37.425499 0)
			(layer "B.Fab")
			(hide yes)
			(effects
				(font
					(size 1 1)
					(thickness 0.15)
				)
				(justify mirror)
			)
		)
		(sheetname "/FPGA power/")
		(sheetfile "fpga-power.kicad_sch")
		(attr smd)
		(fp_rect
			(start -0.9656 0.4572)
			(end 0.9652 -0.4828)
			(stroke
				(width 0.05)
				(type solid)
			)
			(fill no)
			(layer "B.CrtYd")
		)
		(fp_line
			(start 0.498 -0.248)
			(end -0.5 -0.248)
			(stroke
				(width 0.15)
				(type solid)
			)
			(layer "B.Fab")
		)
		(fp_line
			(start -0.5 -0.248)
			(end -0.5 0.25)
			(stroke
				(width 0.15)
				(type solid)
			)
			(layer "B.Fab")
		)
		(fp_line
			(start 0.498 0.25)
			(end 0.498 -0.248)
			(stroke
				(width 0.15)
				(type solid)
			)
			(layer "B.Fab")
		)
		(fp_line
			(start -0.5 0.25)
			(end 0.498 0.25)
			(stroke
				(width 0.15)
				(type solid)
			)
			(layer "B.Fab")
		)
		(pad "1" smd roundrect
			(at -0.5 0)
			(size 0.6 0.6)
			(layers "B.Cu" "B.Mask" "B.Paste")
			(roundrect_rratio 0.25)
			(net 227 "+1V0")
			(pintype "passive")
		)
		(pad "2" smd roundrect
			(at 0.498 0 90)
			(size 0.6 0.6)
			(layers "B.Cu" "B.Mask" "B.Paste")
			(roundrect_rratio 0.25)
			(net 1 "GND")
			(pintype "passive")
		)
	)
	(footprint "antmicro-footprints:R_0402_1005Metric"
		(layer "B.Cu")
		(at 138 142.4 90)
		(descr "Resistor SMD 0402")
		(tags "resistor SMD 0402")
		(property "Reference" "R24"
			(at 3.05 0.35 270)
			(layer "B.SilkS")
			(effects
				(font
					(size 0.7 0.7)
					(thickness 0.15)
				)
				(justify left bottom mirror)
			)
		)
		(property "Value" "R_0R_0402"
			(at -1.011843 -1.772047 270)
			(layer "B.Fab")
			(effects
				(font
					(size 0.7 0.7)
					(thickness 0.15)
				)
				(justify left bottom mirror)
			)
		)
		(property "Datasheet" "https://industrial.panasonic.com/cdbs/www-data/pdf/RDA0000/AOA0000C301.pdf"
			(at 0 0 90)
			(layer "F.Fab")
			(hide yes)
			(effects
				(font
					(size 1.27 1.27)
					(thickness 0.15)
				)
			)
		)
		(property "Author" "Antmicro"
			(at 280.4 4.4 0)
			(layer "B.Fab")
			(hide yes)
			(effects
				(font
					(size 1 1)
					(thickness 0.15)
				)
				(justify mirror)
			)
		)
		(property "Current" "1A"
			(at 280.4 4.4 0)
			(layer "B.Fab")
			(hide yes)
			(effects
				(font
					(size 1 1)
					(thickness 0.15)
				)
				(justify mirror)
			)
		)
		(property "License" "Apache-2.0"
			(at 280.4 4.4 0)
			(layer "B.Fab")
			(hide yes)
			(effects
				(font
					(size 1 1)
					(thickness 0.15)
				)
				(justify mirror)
			)
		)
		(property "MPN" "ERJ2GE0R00X"
			(at 280.4 4.4 0)
			(layer "B.Fab")
			(hide yes)
			(effects
				(font
					(size 1 1)
					(thickness 0.15)
				)
				(justify mirror)
			)
		)
		(property "Manufacturer" "Panasonic"
			(at 280.4 4.4 0)
			(layer "B.Fab")
			(hide yes)
			(effects
				(font
					(size 1 1)
					(thickness 0.15)
				)
				(justify mirror)
			)
		)
		(property "Tolerance" ""
			(at 280.4 4.4 0)
			(layer "B.Fab")
			(hide yes)
			(effects
				(font
					(size 1 1)
					(thickness 0.15)
				)
				(justify mirror)
			)
		)
		(property "Val" "0R"
			(at 280.4 4.4 0)
			(layer "B.Fab")
			(hide yes)
			(effects
				(font
					(size 1 1)
					(thickness 0.15)
				)
				(justify mirror)
			)
		)
		(sheetname "/DDR5 SODIMM/")
		(sheetfile "ddr5-sodimm.kicad_sch")
		(attr exclude_from_pos_files exclude_from_bom dnp)
		(fp_rect
			(start -0.93 0.47)
			(end 0.93 -0.47)
			(stroke
				(width 0.05)
				(type solid)
			)
			(fill no)
			(layer "B.CrtYd")
		)
		(fp_rect
			(start -0.5 0.25)
			(end 0.5 -0.25)
			(stroke
				(width 0.15)
				(type solid)
			)
			(fill no)
			(layer "B.Fab")
		)
		(pad "1" smd roundrect
			(at -0.485 0 90)
			(size 0.59 0.64)
			(layers "B.Cu" "B.Mask" "B.Paste")
			(roundrect_rratio 0.25)
			(net 1 "GND")
			(pintype "passive")
		)
		(pad "2" smd roundrect
			(at 0.485 0 90)
			(size 0.59 0.64)
			(layers "B.Cu" "B.Mask" "B.Paste")
			(roundrect_rratio 0.25)
			(net 172 "/DDR5 SODIMM/VSS_DET2")
			(pintype "passive")
		)
	)
)
